(kicad_pcb
	(version 20241229)
	(generator "pcbnew")
	(generator_version "9.0")
	(general
		(thickness 1.61)
		(legacy_teardrops no)
	)
	(paper "A3")
	(title_block
		(title "SO-DIMM DDR5 Tester")
		(date "2025-11-26")
		(rev "1.3.0")
		(comment 9 "footprints 187-191 of 627")
	)
	(layers
		(0 "F.Cu" signal)
		(4 "In1.Cu" power)
		(6 "In2.Cu" mixed)
		(8 "In3.Cu" power)
		(10 "In4.Cu" mixed)
		(12 "In5.Cu" power)
		(14 "In6.Cu" mixed)
		(16 "In7.Cu" power)
		(18 "In8.Cu" power)
		(20 "In9.Cu" mixed)
		(22 "In10.Cu" power)
		(2 "B.Cu" signal)
		(9 "F.Adhes" user "F.Adhesive")
		(11 "B.Adhes" user "B.Adhesive")
		(13 "F.Paste" user)
		(15 "B.Paste" user)
		(5 "F.SilkS" user "F.Silkscreen")
		(7 "B.SilkS" user "B.Silkscreen")
		(1 "F.Mask" user)
		(3 "B.Mask" user)
		(17 "Dwgs.User" user "User.Drawings")
		(19 "Cmts.User" user "User.Comments")
		(21 "Eco1.User" user "User.Eco1")
		(23 "Eco2.User" user "User.Eco2")
		(25 "Edge.Cuts" user)
		(27 "Margin" user)
		(31 "F.CrtYd" user "F.Courtyard")
		(29 "B.CrtYd" user "B.Courtyard")
		(35 "F.Fab" user)
		(33 "B.Fab" user)
	)
	(footprint "antmicro-footprints:C_0402_1005Metric"
		(layer "F.Cu")
		(at 96.55 182.7 90)
		(descr "Capacitor SMD 0402")
		(tags "capacitor SMD 0402")
		(property "Reference" "C124"
			(at 0 -0.699 90)
			(layer "F.SilkS")
			(hide yes)
			(effects
				(font
					(size 0.7 0.7)
					(thickness 0.15)
				)
				(justify left bottom)
			)
		)
		(property "Value" "C_100n_0402"
			(at -1.022927 2.155213 90)
			(layer "F.Fab")
			(effects
				(font
					(size 0.7 0.7)
					(thickness 0.15)
				)
				(justify left bottom)
			)
		)
		(property "Datasheet" "https://www.murata.com/products/productdetail?partno=GRM155R61H104KE14%23"
			(at 0 0 90)
			(layer "F.Fab")
			(hide yes)
			(effects
				(font
					(size 1.27 1.27)
					(thickness 0.15)
				)
			)
		)
		(property "Author" "Antmicro"
			(at 279.25 86.15 0)
			(layer "F.Fab")
			(hide yes)
			(effects
				(font
					(size 1 1)
					(thickness 0.15)
				)
			)
		)
		(property "Dielectric" "X5R"
			(at 279.25 86.15 0)
			(layer "F.Fab")
			(hide yes)
			(effects
				(font
					(size 1 1)
					(thickness 0.15)
				)
			)
		)
		(property "License" "Apache-2.0"
			(at 279.25 86.15 0)
			(layer "F.Fab")
			(hide yes)
			(effects
				(font
					(size 1 1)
					(thickness 0.15)
				)
			)
		)
		(property "MPN" "GRM155R61H104KE14D"
			(at 279.25 86.15 0)
			(layer "F.Fab")
			(hide yes)
			(effects
				(font
					(size 1 1)
					(thickness 0.15)
				)
			)
		)
		(property "Manufacturer" "Murata"
			(at 279.25 86.15 0)
			(layer "F.Fab")
			(hide yes)
			(effects
				(font
					(size 1 1)
					(thickness 0.15)
				)
			)
		)
		(property "Val" "100n"
			(at 279.25 86.15 0)
			(layer "F.Fab")
			(hide yes)
			(effects
				(font
					(size 1 1)
					(thickness 0.15)
				)
			)
		)
		(property "Voltage" "50V"
			(at 279.25 86.15 0)
			(layer "F.Fab")
			(hide yes)
			(effects
				(font
					(size 1 1)
					(thickness 0.15)
				)
			)
		)
		(sheetname "/Debug FTDI/")
		(sheetfile "debug-ftdi.kicad_sch")
		(attr smd)
		(fp_rect
			(start -0.9659 -0.481258)
			(end 0.9649 0.458742)
			(stroke
				(width 0.05)
				(type solid)
			)
			(fill no)
			(layer "F.CrtYd")
		)
		(fp_line
			(start 0.499 -0.25)
			(end 0.499 0.248)
			(stroke
				(width 0.15)
				(type solid)
			)
			(layer "F.Fab")
		)
		(fp_line
			(start -0.499 -0.25)
			(end 0.499 -0.25)
			(stroke
				(width 0.15)
				(type solid)
			)
			(layer "F.Fab")
		)
		(fp_line
			(start 0.499 0.248)
			(end -0.499 0.248)
			(stroke
				(width 0.15)
				(type solid)
			)
			(layer "F.Fab")
		)
		(fp_line
			(start -0.499 0.248)
			(end -0.499 -0.25)
			(stroke
				(width 0.15)
				(type solid)
			)
			(layer "F.Fab")
		)
		(pad "1" smd roundrect
			(at -0.484 0 90)
			(size 0.59 0.64)
			(layers "F.Cu" "F.Mask" "F.Paste")
			(roundrect_rratio 0.25)
			(net 1 "GND")
			(pintype "passive")
		)
		(pad "2" smd roundrect
			(at 0.484 0 90)
			(size 0.59 0.64)
			(layers "F.Cu" "F.Mask" "F.Paste")
			(roundrect_rratio 0.25)
			(net 200 "+3V3")
			(pintype "passive")
		)
	)
	(footprint "antmicro-footprints:C_Pol_EIA-B"
		(layer "F.Cu")
		(at 129.9 191.9 -90)
		(property "Reference" "C38"
			(at 0 -2.3 270)
			(layer "F.SilkS")
			(hide yes)
			(effects
				(font
					(size 0.7 0.7)
					(thickness 0.15)
				)
				(justify left bottom)
			)
		)
		(property "Value" "C_Pol_330u_6.3V_KEMET-T520-B"
			(at 0 2.85 270)
			(layer "F.Fab")
			(effects
				(font
					(size 0.7 0.7)
					(thickness 0.15)
				)
				(justify left bottom)
			)
		)
		(property "Datasheet" "https://content.kemet.com/datasheets/KEM_T2076_T52X-530.pdf"
			(at 0 0 270)
			(layer "F.Fab")
			(hide yes)
			(effects
				(font
					(size 1.27 1.27)
					(thickness 0.15)
				)
			)
		)
		(property "Author" "Antmicro"
			(at -62 321.8 0)
			(layer "F.Fab")
			(hide yes)
			(effects
				(font
					(size 1 1)
					(thickness 0.15)
				)
			)
		)
		(property "License" "Apache-2.0"
			(at -62 321.8 0)
			(layer "F.Fab")
			(hide yes)
			(effects
				(font
					(size 1 1)
					(thickness 0.15)
				)
			)
		)
		(property "MPN" "T520B337M006ATE040"
			(at -62 321.8 0)
			(layer "F.Fab")
			(hide yes)
			(effects
				(font
					(size 1 1)
					(thickness 0.15)
				)
			)
		)
		(property "Manufacturer" "KEMET"
			(at -62 321.8 0)
			(layer "F.Fab")
			(hide yes)
			(effects
				(font
					(size 1 1)
					(thickness 0.15)
				)
			)
		)
		(property "Val" "330u/6.3V"
			(at -62 321.8 0)
			(layer "F.Fab")
			(hide yes)
			(effects
				(font
					(size 1 1)
					(thickness 0.15)
				)
			)
		)
		(property "Voltage" "6.3V"
			(at -62 321.8 0)
			(layer "F.Fab")
			(hide yes)
			(effects
				(font
					(size 1 1)
					(thickness 0.15)
				)
			)
		)
		(sheetname "/FPGA power/")
		(sheetfile "fpga-power.kicad_sch")
		(zone_connect 2)
		(attr smd)
		(fp_line
			(start 1.8 1.6)
			(end -1.8 1.6)
			(stroke
				(width 0.15)
				(type solid)
			)
			(layer "F.SilkS")
		)
		(fp_line
			(start -1.8 1.3)
			(end -1.8 1.6)
			(stroke
				(width 0.15)
				(type solid)
			)
			(layer "F.SilkS")
		)
		(fp_line
			(start 1.8 1.3)
			(end 1.8 1.6)
			(stroke
				(width 0.15)
				(type solid)
			)
			(layer "F.SilkS")
		)
		(fp_line
			(start -1.8 -1.3)
			(end -1.8 -1.6)
			(stroke
				(width 0.15)
				(type solid)
			)
			(layer "F.SilkS")
		)
		(fp_line
			(start 1.8 -1.3)
			(end 1.8 -1.6)
			(stroke
				(width 0.15)
				(type solid)
			)
			(layer "F.SilkS")
		)
		(fp_line
			(start -2.325 -1.475)
			(end -2.325 -1.878)
			(stroke
				(width 0.15)
				(type solid)
			)
			(layer "F.SilkS")
		)
		(fp_line
			(start -1.8 -1.6)
			(end 1.8 -1.6)
			(stroke
				(width 0.15)
				(type solid)
			)
			(layer "F.SilkS")
		)
		(fp_line
			(start -2.521 -1.676)
			(end -2.123 -1.676)
			(stroke
				(width 0.15)
				(type solid)
			)
			(layer "F.SilkS")
		)
		(fp_line
			(start 1.96 1.75)
			(end -1.97 1.75)
			(stroke
				(width 0.05)
				(type solid)
			)
			(layer "F.CrtYd")
		)
		(fp_line
			(start -1.97 1.35)
			(end -1.97 1.75)
			(stroke
				(width 0.05)
				(type solid)
			)
			(layer "F.CrtYd")
		)
		(fp_line
			(start -1.97 1.35)
			(end -2.41 1.35)
			(stroke
				(width 0.05)
				(type solid)
			)
			(layer "F.CrtYd")
		)
		(fp_line
			(start 1.96 1.35)
			(end 1.96 1.75)
			(stroke
				(width 0.05)
				(type solid)
			)
			(layer "F.CrtYd")
		)
		(fp_line
			(start 2.4 1.35)
			(end 1.96 1.35)
			(stroke
				(width 0.05)
				(type solid)
			)
			(layer "F.CrtYd")
		)
		(fp_line
			(start -2.411 -1.35)
			(end -2.41 1.35)
			(stroke
				(width 0.05)
				(type solid)
			)
			(layer "F.CrtYd")
		)
		(fp_line
			(start -1.97 -1.35)
			(end -2.41 -1.35)
			(stroke
				(width 0.05)
				(type solid)
			)
			(layer "F.CrtYd")
		)
		(fp_line
			(start 2.399 -1.35)
			(end 2.4 1.35)
			(stroke
				(width 0.05)
				(type solid)
			)
			(layer "F.CrtYd")
		)
		(fp_line
			(start 2.399 -1.35)
			(end 1.959 -1.35)
			(stroke
				(width 0.05)
				(type solid)
			)
			(layer "F.CrtYd")
		)
		(fp_line
			(start -1.97 -1.75)
			(end -1.97 -1.35)
			(stroke
				(width 0.05)
				(type solid)
			)
			(layer "F.CrtYd")
		)
		(fp_line
			(start 1.959 -1.75)
			(end 1.959 -1.35)
			(stroke
				(width 0.05)
				(type solid)
			)
			(layer "F.CrtYd")
		)
		(fp_line
			(start 1.959 -1.75)
			(end -1.971 -1.75)
			(stroke
				(width 0.05)
				(type solid)
			)
			(layer "F.CrtYd")
		)
		(fp_line
			(start -1.7 1.324)
			(end -1.551 1.475)
			(stroke
				(width 0.15)
				(type solid)
			)
			(layer "F.Fab")
		)
		(fp_rect
			(start -1.72 -1.5)
			(end 1.719 1.499)
			(stroke
				(width 0.15)
				(type solid)
			)
			(fill no)
			(layer "F.Fab")
		)
		(pad "1" smd roundrect
			(at -1.551 0 270)
			(size 1.2 2.2)
			(layers "F.Cu" "F.Mask" "F.Paste")
			(roundrect_rratio 0.1)
			(net 227 "+1V0")
			(pintype "passive")
		)
		(pad "2" smd roundrect
			(at 1.55 0 270)
			(size 1.2 2.2)
			(layers "F.Cu" "F.Mask" "F.Paste")
			(roundrect_rratio 0.1)
			(net 1 "GND")
			(pintype "passive")
		)
	)
	(footprint "antmicro-footprints:R_1206_3216Metric"
		(layer "F.Cu")
		(at 188.7 189.1 180)
		(property "Reference" "R141"
			(at 0.1 1.2 180)
			(layer "F.SilkS")
			(effects
				(font
					(size 0.7 0.7)
					(thickness 0.15)
				)
				(justify left bottom)
			)
		)
		(property "Value" "R_0R01_1206"
			(at -2.422356 2.103591 180)
			(layer "F.Fab")
			(effects
				(font
					(size 0.7 0.7)
					(thickness 0.15)
				)
				(justify left bottom)
			)
		)
		(property "Datasheet" "https://www.yageo.com/upload/media/product/productsearch/datasheet/rchip/PYu-RL_Group_521_RoHS_L_2.pdf"
			(at 0 0 180)
			(layer "F.Fab")
			(hide yes)
			(effects
				(font
					(size 1.27 1.27)
					(thickness 0.15)
				)
			)
		)
		(property "Author" "Antmicro"
			(at 377.4 378.2 0)
			(layer "F.Fab")
			(hide yes)
			(effects
				(font
					(size 1 1)
					(thickness 0.15)
				)
			)
		)
		(property "License" "Apache-2.0"
			(at 377.4 378.2 0)
			(layer "F.Fab")
			(hide yes)
			(effects
				(font
					(size 1 1)
					(thickness 0.15)
				)
			)
		)
		(property "MPN" "RL1206FR-7W0R01L"
			(at 377.4 378.2 0)
			(layer "F.Fab")
			(hide yes)
			(effects
				(font
					(size 1 1)
					(thickness 0.15)
				)
			)
		)
		(property "Manufacturer" "YAGEO"
			(at 377.4 378.2 0)
			(layer "F.Fab")
			(hide yes)
			(effects
				(font
					(size 1 1)
					(thickness 0.15)
				)
			)
		)
		(property "Tolerance" "1%"
			(at 377.4 378.2 0)
			(layer "F.Fab")
			(hide yes)
			(effects
				(font
					(size 1 1)
					(thickness 0.15)
				)
			)
		)
		(property "Val" "0R01"
			(at 377.4 378.2 0)
			(layer "F.Fab")
			(hide yes)
			(effects
				(font
					(size 1 1)
					(thickness 0.15)
				)
			)
		)
		(sheetname "/Supply/")
		(sheetfile "supply.kicad_sch")
		(attr smd)
		(fp_line
			(start 0 0.9)
			(end 0.498 0.9)
			(stroke
				(width 0.15)
				(type solid)
			)
			(layer "F.SilkS")
		)
		(fp_line
			(start 0 0.9)
			(end -0.5 0.9)
			(stroke
				(width 0.15)
				(type solid)
			)
			(layer "F.SilkS")
		)
		(fp_line
			(start 0 -0.902)
			(end 0.498 -0.902)
			(stroke
				(width 0.15)
				(type solid)
			)
			(layer "F.SilkS")
		)
		(fp_line
			(start 0 -0.902)
			(end -0.5 -0.902)
			(stroke
				(width 0.15)
				(type solid)
			)
			(layer "F.SilkS")
		)
		(fp_rect
			(start -2.25 -1.05)
			(end 2.25 1.05)
			(stroke
				(width 0.05)
				(type solid)
			)
			(fill no)
			(layer "F.CrtYd")
		)
		(fp_line
			(start 1.6 -0.802)
			(end 1.6 0.8)
			(stroke
				(width 0.15)
				(type solid)
			)
			(layer "F.Fab")
		)
		(fp_line
			(start -1.601 0.8)
			(end 1.6 0.8)
			(stroke
				(width 0.15)
				(type solid)
			)
			(layer "F.Fab")
		)
		(fp_line
			(start -1.601 -0.802)
			(end 1.6 -0.802)
			(stroke
				(width 0.15)
				(type solid)
			)
			(layer "F.Fab")
		)
		(fp_line
			(start -1.601 -0.802)
			(end -1.601 0.8)
			(stroke
				(width 0.15)
				(type solid)
			)
			(layer "F.Fab")
		)
		(pad "1" smd roundrect
			(at -1.5 0 180)
			(size 1.2 1.8)
			(layers "F.Cu" "F.Mask" "F.Paste")
			(roundrect_rratio 0.15)
			(net 42 "/Supply/MGTAVCC_local")
			(pintype "passive")
		)
		(pad "2" smd roundrect
			(at 1.499 0 180)
			(size 1.2 1.8)
			(layers "F.Cu" "F.Mask" "F.Paste")
			(roundrect_rratio 0.15)
			(net 187 "+1V0_MGTAVCC")
			(pintype "passive")
		)
	)
	(footprint "antmicro-footprints:LED_0603_1608Metric_G"
		(layer "F.Cu")
		(at 96.3 197.1 -90)
		(descr "LED SMD 0603 Green")
		(tags "LED SMD 0603 Green")
		(property "Reference" "D12"
			(at -0.001 -0.901 270)
			(layer "F.SilkS")
			(hide yes)
			(effects
				(font
					(size 0.7 0.7)
					(thickness 0.15)
				)
				(justify left bottom)
			)
		)
		(property "Value" "LED_G_0603_KP-1608CGCK"
			(at -0.001 1.599 270)
			(layer "F.Fab")
			(effects
				(font
					(size 0.7 0.7)
					(thickness 0.15)
				)
				(justify left bottom)
			)
		)
		(property "Datasheet" "http://www.farnell.com/datasheets/2045956.pdf"
			(at 0 0 270)
			(layer "F.Fab")
			(hide yes)
			(effects
				(font
					(size 1.27 1.27)
					(thickness 0.15)
				)
			)
		)
		(property "Author" "Antmicro"
			(at -100.8 293.4 0)
			(layer "F.Fab")
			(hide yes)
			(effects
				(font
					(size 1 1)
					(thickness 0.15)
				)
			)
		)
		(property "License" "Apache-2.0"
			(at -100.8 293.4 0)
			(layer "F.Fab")
			(hide yes)
			(effects
				(font
					(size 1 1)
					(thickness 0.15)
				)
			)
		)
		(property "MPN" "KP-1608CGCK"
			(at -100.8 293.4 0)
			(layer "F.Fab")
			(hide yes)
			(effects
				(font
					(size 1 1)
					(thickness 0.15)
				)
			)
		)
		(property "Manufacturer" "Kingbright"
			(at -100.8 293.4 0)
			(layer "F.Fab")
			(hide yes)
			(effects
				(font
					(size 1 1)
					(thickness 0.15)
				)
			)
		)
		(sheetname "/Debug FTDI/")
		(sheetfile "debug-ftdi.kicad_sch")
		(attr smd)
		(fp_line
			(start -0.271 0.348)
			(end 0.269 0.348)
			(stroke
				(width 0.15)
				(type solid)
			)
			(layer "F.SilkS")
		)
		(fp_line
			(start 1.249 0.319)
			(end 1.249 -0.321)
			(stroke
				(width 0.15)
				(type solid)
			)
			(layer "F.SilkS")
		)
		(fp_line
			(start -0.107 -0.001)
			(end -0.291 -0.001)
			(stroke
				(width 0.1)
				(type solid)
			)
			(layer "F.SilkS")
		)
		(fp_line
			(start 0.092 -0.001)
			(end -0.107 0.198)
			(stroke
				(width 0.1)
				(type solid)
			)
			(layer "F.SilkS")
		)
		(fp_line
			(start 0.092 -0.001)
			(end 0.292 -0.001)
			(stroke
				(width 0.1)
				(type solid)
			)
			(layer "F.SilkS")
		)
		(fp_line
			(start -0.107 -0.201)
			(end -0.107 0.198)
			(stroke
				(width 0.1)
				(type solid)
			)
			(layer "F.SilkS")
		)
		(fp_line
			(start -0.107 -0.201)
			(end 0.092 -0.001)
			(stroke
				(width 0.1)
				(type solid)
			)
			(layer "F.SilkS")
		)
		(fp_line
			(start 0.092 -0.201)
			(end 0.092 0.198)
			(stroke
				(width 0.1)
				(type solid)
			)
			(layer "F.SilkS")
		)
		(fp_line
			(start -0.271 -0.349)
			(end 0.269 -0.349)
			(stroke
				(width 0.15)
				(type solid)
			)
			(layer "F.SilkS")
		)
		(fp_rect
			(start -1.2192 -0.6096)
			(end 1.27 0.6016)
			(stroke
				(width 0.05)
				(type solid)
			)
			(fill no)
			(layer "F.CrtYd")
		)
		(fp_line
			(start -0.202 0.201)
			(end 0.1 -0.001)
			(stroke
				(width 0.15)
				(type solid)
			)
			(layer "F.Fab")
		)
		(fp_line
			(start 0.198 0.201)
			(end 0.198 -0.101)
			(stroke
				(width 0.15)
				(type solid)
			)
			(layer "F.Fab")
		)
		(fp_line
			(start -0.849 0.025)
			(end -0.442 0.381)
			(stroke
				(width 0.15)
				(type solid)
			)
			(layer "F.Fab")
		)
		(fp_line
			(start -0.6 -0.001)
			(end -0.202 -0.001)
			(stroke
				(width 0.15)
				(type solid)
			)
			(layer "F.Fab")
		)
		(fp_line
			(start -0.202 -0.001)
			(end -0.202 0.201)
			(stroke
				(width 0.15)
				(type solid)
			)
			(layer "F.Fab")
		)
		(fp_line
			(start 0.1 -0.001)
			(end -0.202 -0.201)
			(stroke
				(width 0.15)
				(type solid)
			)
			(layer "F.Fab")
		)
		(fp_line
			(start 0.198 -0.001)
			(end 0.596 -0.001)
			(stroke
				(width 0.15)
				(type solid)
			)
			(layer "F.Fab")
		)
		(fp_line
			(start -0.202 -0.201)
			(end -0.202 -0.001)
			(stroke
				(width 0.15)
				(type solid)
			)
			(layer "F.Fab")
		)
		(fp_line
			(start 0.198 -0.201)
			(end 0.198 -0.101)
			(stroke
				(width 0.15)
				(type solid)
			)
			(layer "F.Fab")
		)
		(fp_rect
			(start -0.849 -0.401)
			(end 0.849 0.401)
			(stroke
				(width 0.15)
				(type solid)
			)
			(fill no)
			(layer "F.Fab")
		)
		(pad "1" smd rect
			(at -0.751 -0.001 90)
			(size 0.8 0.8)
			(layers "F.Cu" "F.Mask" "F.Paste")
			(net 317 "Net-(D12-Pad1)")
			(pinfunction "1")
			(pintype "passive")
		)
		(pad "2" smd rect
			(at 0.749 -0.001 90)
			(size 0.8 0.8)
			(layers "F.Cu" "F.Mask" "F.Paste")
			(net 1 "GND")
			(pinfunction "2")
			(pintype "passive")
		)
	)
	(footprint "antmicro-footprints:R_0402_1005Metric"
		(layer "F.Cu")
		(at 96.3 194.83 90)
		(descr "Resistor SMD 0402")
		(tags "resistor SMD 0402")
		(property "Reference" "R66"
			(at -1.122484 -0.772697 90)
			(layer "F.SilkS")
			(hide yes)
			(effects
				(font
					(size 0.7 0.7)
					(thickness 0.15)
				)
				(justify left bottom)
			)
		)
		(property "Value" "R_330R_0402"
			(at -1.011843 1.772047 90)
			(layer "F.Fab")
			(effects
				(font
					(size 0.7 0.7)
					(thickness 0.15)
				)
				(justify left bottom)
			)
		)
		(property "Datasheet" "https://www.bourns.com/docs/product-datasheets/cr.pdf"
			(at 0 0 90)
			(layer "F.Fab")
			(hide yes)
			(effects
				(font
					(size 1.27 1.27)
					(thickness 0.15)
				)
			)
		)
		(property "Author" "Antmicro"
			(at 291.13 98.53 0)
			(layer "F.Fab")
			(hide yes)
			(effects
				(font
					(size 1 1)
					(thickness 0.15)
				)
			)
		)
		(property "License" "Apache-2.0"
			(at 291.13 98.53 0)
			(layer "F.Fab")
			(hide yes)
			(effects
				(font
					(size 1 1)
					(thickness 0.15)
				)
			)
		)
		(property "MPN" "CR0402-FX-3300GLF"
			(at 291.13 98.53 0)
			(layer "F.Fab")
			(hide yes)
			(effects
				(font
					(size 1 1)
					(thickness 0.15)
				)
			)
		)
		(property "Manufacturer" "Bourns"
			(at 291.13 98.53 0)
			(layer "F.Fab")
			(hide yes)
			(effects
				(font
					(size 1 1)
					(thickness 0.15)
				)
			)
		)
		(property "Tolerance" "1%"
			(at 291.13 98.53 0)
			(layer "F.Fab")
			(hide yes)
			(effects
				(font
					(size 1 1)
					(thickness 0.15)
				)
			)
		)
		(property "Val" "330R"
			(at 291.13 98.53 0)
			(layer "F.Fab")
			(hide yes)
			(effects
				(font
					(size 1 1)
					(thickness 0.15)
				)
			)
		)
		(sheetname "/Debug FTDI/")
		(sheetfile "debug-ftdi.kicad_sch")
		(attr smd)
		(fp_rect
			(start -0.93 -0.47)
			(end 0.93 0.47)
			(stroke
				(width 0.05)
				(type solid)
			)
			(fill no)
			(layer "F.CrtYd")
		)
		(fp_rect
			(start -0.5 -0.25)
			(end 0.5 0.25)
			(stroke
				(width 0.15)
				(type solid)
			)
			(fill no)
			(layer "F.Fab")
		)
		(pad "1" smd roundrect
			(at -0.485 0 90)
			(size 0.59 0.64)
			(layers "F.Cu" "F.Mask" "F.Paste")
			(roundrect_rratio 0.25)
			(net 317 "Net-(D12-Pad1)")
			(pintype "passive")
		)
		(pad "2" smd roundrect
			(at 0.485 0 90)
			(size 0.59 0.64)
			(layers "F.Cu" "F.Mask" "F.Paste")
			(roundrect_rratio 0.25)
			(net 658 "/Debug FTDI/LED_TX1")
			(pintype "passive")
		)
	)
)
